(kicad_pcb
	(version 20241229)
	(generator "pcbnew")
	(generator_version "9.0")
	(general
		(thickness 1.599998)
		(legacy_teardrops no)
	)
	(paper "A4")
	(title_block
		(date "2023-02-12")
		(rev "1.1.5")
		(comment 9 "footprints 254-260 of 473")
	)
	(layers
		(0 "F.Cu" signal)
		(4 "In1.Cu" power "In1.GND")
		(6 "In2.Cu" signal)
		(8 "In3.Cu" power "In3.GND")
		(10 "In4.Cu" power "In4.VCC")
		(12 "In5.Cu" signal)
		(14 "In6.Cu" power "In6.VCC")
		(2 "B.Cu" signal)
		(9 "F.Adhes" user "F.Adhesive")
		(11 "B.Adhes" user "B.Adhesive")
		(13 "F.Paste" user)
		(15 "B.Paste" user)
		(5 "F.SilkS" user "F.Silkscreen")
		(7 "B.SilkS" user "B.Silkscreen")
		(1 "F.Mask" user)
		(3 "B.Mask" user)
		(17 "Dwgs.User" user "User.Drawings")
		(19 "Cmts.User" user "User.Comments")
		(21 "Eco1.User" user "User.Eco1")
		(23 "Eco2.User" user "User.Eco2")
		(25 "Edge.Cuts" user)
		(27 "Margin" user)
		(31 "F.CrtYd" user "F.Courtyard")
		(29 "B.CrtYd" user "B.Courtyard")
		(35 "F.Fab" user)
		(33 "B.Fab" user)
	)
	(footprint "antmicro-footprints:C_0402_1005Metric"
		(layer "F.Cu")
		(at 123.14 83.724 180)
		(descr "Capacitor SMD 0402")
		(tags "capacitor SMD 0402")
		(property "Reference" "C179"
			(at 1.94 2.524 180)
			(layer "F.SilkS")
			(effects
				(font
					(size 0.7 0.7)
					(thickness 0.15)
				)
				(justify left bottom)
			)
		)
		(property "Value" "C_1u_0402"
			(at 0 1.4 180)
			(layer "F.Fab")
			(effects
				(font
					(size 0.7 0.7)
					(thickness 0.15)
				)
				(justify left bottom)
			)
		)
		(property "Description" " "
			(at 0 0 180)
			(layer "F.Fab")
			(hide yes)
			(effects
				(font
					(size 1.27 1.27)
					(thickness 0.15)
				)
			)
		)
		(property "Author" "Antmicro"
			(at 246.28 167.448 0)
			(layer "F.Fab")
			(hide yes)
			(effects
				(font
					(size 1 1)
					(thickness 0.15)
				)
			)
		)
		(property "Dielectric" ""
			(at 246.28 167.448 0)
			(layer "F.Fab")
			(hide yes)
			(effects
				(font
					(size 1 1)
					(thickness 0.15)
				)
			)
		)
		(property "License" "Apache-2.0"
			(at 246.28 167.448 0)
			(layer "F.Fab")
			(hide yes)
			(effects
				(font
					(size 1 1)
					(thickness 0.15)
				)
			)
		)
		(property "MPN" "C1005X6S1A105K050BC"
			(at 246.28 167.448 0)
			(layer "F.Fab")
			(hide yes)
			(effects
				(font
					(size 1 1)
					(thickness 0.15)
				)
			)
		)
		(property "Manufacturer" "TDK"
			(at 246.28 167.448 0)
			(layer "F.Fab")
			(hide yes)
			(effects
				(font
					(size 1 1)
					(thickness 0.15)
				)
			)
		)
		(property "Val" "1u"
			(at 246.28 167.448 0)
			(layer "F.Fab")
			(hide yes)
			(effects
				(font
					(size 1 1)
					(thickness 0.15)
				)
			)
		)
		(property "Voltage" ""
			(at 246.28 167.448 0)
			(layer "F.Fab")
			(hide yes)
			(effects
				(font
					(size 1 1)
					(thickness 0.15)
				)
			)
		)
		(sheetname "Supply")
		(sheetfile "supply.kicad_sch")
		(attr smd)
		(fp_rect
			(start -0.94 -0.47)
			(end 0.94 0.47)
			(stroke
				(width 0.05)
				(type solid)
			)
			(fill no)
			(layer "F.CrtYd")
		)
		(fp_rect
			(start -0.499 -0.249)
			(end 0.499 0.249)
			(stroke
				(width 0.15)
				(type solid)
			)
			(fill no)
			(layer "F.Fab")
		)
		(pad "1" smd roundrect
			(at -0.484 0 180)
			(size 0.59 0.64)
			(layers "F.Cu" "F.Mask" "F.Paste")
			(roundrect_rratio 0.25)
			(net 587 "/Supply/1V1_REG")
			(pintype "passive")
		)
		(pad "2" smd roundrect
			(at 0.484 0 180)
			(size 0.59 0.64)
			(layers "F.Cu" "F.Mask" "F.Paste")
			(roundrect_rratio 0.25)
			(net 5 "GND")
			(pintype "passive")
		)
	)
	(footprint "antmicro-footprints:C_0402_1005Metric"
		(layer "F.Cu")
		(at 123.6475 99.449 180)
		(descr "Capacitor SMD 0402")
		(tags "capacitor SMD 0402")
		(property "Reference" "C166"
			(at 3.5475 -0.351 180)
			(layer "F.SilkS")
			(effects
				(font
					(size 0.7 0.7)
					(thickness 0.15)
				)
				(justify left bottom)
			)
		)
		(property "Value" "C_1u_0402"
			(at 0 1.4 180)
			(layer "F.Fab")
			(effects
				(font
					(size 0.7 0.7)
					(thickness 0.15)
				)
				(justify left bottom)
			)
		)
		(property "Description" " "
			(at 0 0 180)
			(layer "F.Fab")
			(hide yes)
			(effects
				(font
					(size 1.27 1.27)
					(thickness 0.15)
				)
			)
		)
		(property "Author" "Antmicro"
			(at 247.295 198.898 0)
			(layer "F.Fab")
			(hide yes)
			(effects
				(font
					(size 1 1)
					(thickness 0.15)
				)
			)
		)
		(property "Dielectric" ""
			(at 247.295 198.898 0)
			(layer "F.Fab")
			(hide yes)
			(effects
				(font
					(size 1 1)
					(thickness 0.15)
				)
			)
		)
		(property "License" "Apache-2.0"
			(at 247.295 198.898 0)
			(layer "F.Fab")
			(hide yes)
			(effects
				(font
					(size 1 1)
					(thickness 0.15)
				)
			)
		)
		(property "MPN" "C1005X6S1A105K050BC"
			(at 247.295 198.898 0)
			(layer "F.Fab")
			(hide yes)
			(effects
				(font
					(size 1 1)
					(thickness 0.15)
				)
			)
		)
		(property "Manufacturer" "TDK"
			(at 247.295 198.898 0)
			(layer "F.Fab")
			(hide yes)
			(effects
				(font
					(size 1 1)
					(thickness 0.15)
				)
			)
		)
		(property "Val" "1u"
			(at 247.295 198.898 0)
			(layer "F.Fab")
			(hide yes)
			(effects
				(font
					(size 1 1)
					(thickness 0.15)
				)
			)
		)
		(property "Voltage" ""
			(at 247.295 198.898 0)
			(layer "F.Fab")
			(hide yes)
			(effects
				(font
					(size 1 1)
					(thickness 0.15)
				)
			)
		)
		(sheetname "Supply")
		(sheetfile "supply.kicad_sch")
		(attr smd)
		(fp_rect
			(start -0.94 -0.47)
			(end 0.94 0.47)
			(stroke
				(width 0.05)
				(type solid)
			)
			(fill no)
			(layer "F.CrtYd")
		)
		(fp_rect
			(start -0.499 -0.249)
			(end 0.499 0.249)
			(stroke
				(width 0.15)
				(type solid)
			)
			(fill no)
			(layer "F.Fab")
		)
		(pad "1" smd roundrect
			(at -0.484 0 180)
			(size 0.59 0.64)
			(layers "F.Cu" "F.Mask" "F.Paste")
			(roundrect_rratio 0.25)
			(net 593 "/Supply/1V0_VCC_INT")
			(pintype "passive")
		)
		(pad "2" smd roundrect
			(at 0.484 0 180)
			(size 0.59 0.64)
			(layers "F.Cu" "F.Mask" "F.Paste")
			(roundrect_rratio 0.25)
			(net 5 "GND")
			(pintype "passive")
		)
	)
	(footprint "antmicro-footprints:C_0402_1005Metric"
		(layer "F.Cu")
		(at 115.397806 86.824)
		(descr "Capacitor SMD 0402")
		(tags "capacitor SMD 0402")
		(property "Reference" "C158"
			(at -3.597806 0.376 0)
			(layer "F.SilkS")
			(effects
				(font
					(size 0.7 0.7)
					(thickness 0.15)
				)
				(justify left bottom)
			)
		)
		(property "Value" "C_100n_6V3_0402"
			(at 0 1.4 0)
			(layer "F.Fab")
			(effects
				(font
					(size 0.7 0.7)
					(thickness 0.15)
				)
				(justify left bottom)
			)
		)
		(property "Description" " "
			(at 0 0 0)
			(layer "F.Fab")
			(hide yes)
			(effects
				(font
					(size 1.27 1.27)
					(thickness 0.15)
				)
			)
		)
		(property "Author" "Antmicro"
			(at 0 0 0)
			(layer "F.Fab")
			(hide yes)
			(effects
				(font
					(size 1 1)
					(thickness 0.15)
				)
			)
		)
		(property "Dielectric" ""
			(at 0 0 0)
			(layer "F.Fab")
			(hide yes)
			(effects
				(font
					(size 1 1)
					(thickness 0.15)
				)
			)
		)
		(property "License" "Apache-2.0"
			(at 0 0 0)
			(layer "F.Fab")
			(hide yes)
			(effects
				(font
					(size 1 1)
					(thickness 0.15)
				)
			)
		)
		(property "MPN" "0402X104K6R3CT"
			(at 0 0 0)
			(layer "F.Fab")
			(hide yes)
			(effects
				(font
					(size 1 1)
					(thickness 0.15)
				)
			)
		)
		(property "Manufacturer" "Walsin"
			(at 0 0 0)
			(layer "F.Fab")
			(hide yes)
			(effects
				(font
					(size 1 1)
					(thickness 0.15)
				)
			)
		)
		(property "Val" "100n"
			(at 0 0 0)
			(layer "F.Fab")
			(hide yes)
			(effects
				(font
					(size 1 1)
					(thickness 0.15)
				)
			)
		)
		(property "Voltage" ""
			(at 0 0 0)
			(layer "F.Fab")
			(hide yes)
			(effects
				(font
					(size 1 1)
					(thickness 0.15)
				)
			)
		)
		(sheetname "Supply")
		(sheetfile "supply.kicad_sch")
		(attr smd)
		(fp_rect
			(start -0.94 -0.47)
			(end 0.94 0.47)
			(stroke
				(width 0.05)
				(type solid)
			)
			(fill no)
			(layer "F.CrtYd")
		)
		(fp_rect
			(start -0.499 -0.249)
			(end 0.499 0.249)
			(stroke
				(width 0.15)
				(type solid)
			)
			(fill no)
			(layer "F.Fab")
		)
		(pad "1" smd roundrect
			(at -0.484 0)
			(size 0.59 0.64)
			(layers "F.Cu" "F.Mask" "F.Paste")
			(roundrect_rratio 0.25)
			(net 584 "/Supply/1V8_SW")
			(pintype "passive")
		)
		(pad "2" smd roundrect
			(at 0.484 0)
			(size 0.59 0.64)
			(layers "F.Cu" "F.Mask" "F.Paste")
			(roundrect_rratio 0.25)
			(net 552 "/Supply/1V8_BST")
			(pintype "passive")
		)
	)
	(footprint "antmicro-footprints:C_0402_1005Metric"
		(layer "F.Cu")
		(at 187.1 111.85 90)
		(descr "Capacitor SMD 0402")
		(tags "capacitor SMD 0402")
		(property "Reference" "C165"
			(at 0.751 0.4 90)
			(layer "F.SilkS")
			(effects
				(font
					(size 0.7 0.7)
					(thickness 0.15)
				)
				(justify left bottom)
			)
		)
		(property "Value" "C_1u_0402"
			(at 0 1.4 90)
			(layer "F.Fab")
			(effects
				(font
					(size 0.7 0.7)
					(thickness 0.15)
				)
				(justify left bottom)
			)
		)
		(property "Description" " "
			(at 0 0 90)
			(layer "F.Fab")
			(hide yes)
			(effects
				(font
					(size 1.27 1.27)
					(thickness 0.15)
				)
			)
		)
		(property "Author" "Antmicro"
			(at 298.95 -75.25 0)
			(layer "F.Fab")
			(hide yes)
			(effects
				(font
					(size 1 1)
					(thickness 0.15)
				)
			)
		)
		(property "Dielectric" ""
			(at 298.95 -75.25 0)
			(layer "F.Fab")
			(hide yes)
			(effects
				(font
					(size 1 1)
					(thickness 0.15)
				)
			)
		)
		(property "License" "Apache-2.0"
			(at 298.95 -75.25 0)
			(layer "F.Fab")
			(hide yes)
			(effects
				(font
					(size 1 1)
					(thickness 0.15)
				)
			)
		)
		(property "MPN" "C1005X6S1A105K050BC"
			(at 298.95 -75.25 0)
			(layer "F.Fab")
			(hide yes)
			(effects
				(font
					(size 1 1)
					(thickness 0.15)
				)
			)
		)
		(property "Manufacturer" "TDK"
			(at 298.95 -75.25 0)
			(layer "F.Fab")
			(hide yes)
			(effects
				(font
					(size 1 1)
					(thickness 0.15)
				)
			)
		)
		(property "Val" "1u"
			(at 298.95 -75.25 0)
			(layer "F.Fab")
			(hide yes)
			(effects
				(font
					(size 1 1)
					(thickness 0.15)
				)
			)
		)
		(property "Voltage" ""
			(at 298.95 -75.25 0)
			(layer "F.Fab")
			(hide yes)
			(effects
				(font
					(size 1 1)
					(thickness 0.15)
				)
			)
		)
		(sheetname "Supply")
		(sheetfile "supply.kicad_sch")
		(attr smd)
		(fp_rect
			(start -0.94 -0.47)
			(end 0.94 0.47)
			(stroke
				(width 0.05)
				(type solid)
			)
			(fill no)
			(layer "F.CrtYd")
		)
		(fp_rect
			(start -0.499 -0.249)
			(end 0.499 0.249)
			(stroke
				(width 0.15)
				(type solid)
			)
			(fill no)
			(layer "F.Fab")
		)
		(pad "1" smd roundrect
			(at -0.484 0 90)
			(size 0.59 0.64)
			(layers "F.Cu" "F.Mask" "F.Paste")
			(roundrect_rratio 0.25)
			(net 597 "/Supply/1V2_VCC_INT")
			(pintype "passive")
		)
		(pad "2" smd roundrect
			(at 0.484 0 90)
			(size 0.59 0.64)
			(layers "F.Cu" "F.Mask" "F.Paste")
			(roundrect_rratio 0.25)
			(net 5 "GND")
			(pintype "passive")
		)
	)
	(footprint "antmicro-footprints:R_0402_1005Metric"
		(layer "F.Cu")
		(at 118.275 101.549 180)
		(descr "Resistor SMD 0402")
		(tags "resistor SMD 0402")
		(property "Reference" "R114"
			(at 0.875 2.549 180)
			(layer "F.SilkS")
			(effects
				(font
					(size 0.7 0.7)
					(thickness 0.15)
				)
				(justify left bottom)
			)
		)
		(property "Value" "R_100k_0402"
			(at 0 1.4 180)
			(layer "F.Fab")
			(effects
				(font
					(size 0.7 0.7)
					(thickness 0.15)
				)
				(justify left bottom)
			)
		)
		(property "Description" "100k resistor in 0402 package with 1% tolerance"
			(at 0 0 180)
			(layer "F.Fab")
			(hide yes)
			(effects
				(font
					(size 1.27 1.27)
					(thickness 0.15)
				)
			)
		)
		(property "Author" "Antmicro"
			(at 236.55 203.098 0)
			(layer "F.Fab")
			(hide yes)
			(effects
				(font
					(size 1 1)
					(thickness 0.15)
				)
			)
		)
		(property "License" "Apache-2.0"
			(at 236.55 203.098 0)
			(layer "F.Fab")
			(hide yes)
			(effects
				(font
					(size 1 1)
					(thickness 0.15)
				)
			)
		)
		(property "MPN" "CR0402-FX-1003GLF"
			(at 236.55 203.098 0)
			(layer "F.Fab")
			(hide yes)
			(effects
				(font
					(size 1 1)
					(thickness 0.15)
				)
			)
		)
		(property "Manufacturer" "Bourns"
			(at 236.55 203.098 0)
			(layer "F.Fab")
			(hide yes)
			(effects
				(font
					(size 1 1)
					(thickness 0.15)
				)
			)
		)
		(property "Tolerance" "1%"
			(at 236.55 203.098 0)
			(layer "F.Fab")
			(hide yes)
			(effects
				(font
					(size 1 1)
					(thickness 0.15)
				)
			)
		)
		(property "Val" "100k"
			(at 236.55 203.098 0)
			(layer "F.Fab")
			(hide yes)
			(effects
				(font
					(size 1 1)
					(thickness 0.15)
				)
			)
		)
		(sheetname "Supply")
		(sheetfile "supply.kicad_sch")
		(attr smd)
		(fp_rect
			(start -0.93 -0.47)
			(end 0.93 0.47)
			(stroke
				(width 0.05)
				(type solid)
			)
			(fill no)
			(layer "F.CrtYd")
		)
		(fp_rect
			(start -0.5 -0.25)
			(end 0.5 0.25)
			(stroke
				(width 0.15)
				(type solid)
			)
			(fill no)
			(layer "F.Fab")
		)
		(pad "1" smd roundrect
			(at -0.485 0 180)
			(size 0.59 0.64)
			(layers "F.Cu" "F.Mask" "F.Paste")
			(roundrect_rratio 0.25)
			(net 470 "/Supply/VCC_IO_EN")
			(pintype "passive")
		)
		(pad "2" smd roundrect
			(at 0.485 0 180)
			(size 0.59 0.64)
			(layers "F.Cu" "F.Mask" "F.Paste")
			(roundrect_rratio 0.25)
			(net 577 "/Supply/3V3_EN")
			(pintype "passive")
		)
	)
	(footprint "antmicro-footprints:SOT-523"
		(layer "F.Cu")
		(at 142.3825 84.699 90)
		(property "Reference" "Q11"
			(at 0.599 -2.5825 0)
			(layer "F.SilkS")
			(effects
				(font
					(size 0.7 0.7)
					(thickness 0.15)
				)
				(justify left bottom)
			)
		)
		(property "Value" "DMG1012T-7"
			(at 0.1 1.824 90)
			(layer "F.Fab")
			(effects
				(font
					(size 0.7 0.7)
					(thickness 0.15)
				)
				(justify left bottom)
			)
		)
		(property "Author" "Antmicro"
			(at 227.0815 -57.6835 0)
			(layer "F.Fab")
			(hide yes)
			(effects
				(font
					(size 1 1)
					(thickness 0.15)
				)
			)
		)
		(property "License" "Apache-2.0"
			(at 227.0815 -57.6835 0)
			(layer "F.Fab")
			(hide yes)
			(effects
				(font
					(size 1 1)
					(thickness 0.15)
				)
			)
		)
		(property "MPN" "DMG1012T-7"
			(at 227.0815 -57.6835 0)
			(layer "F.Fab")
			(hide yes)
			(effects
				(font
					(size 1 1)
					(thickness 0.15)
				)
			)
		)
		(property "Manufacturer" "Diodes Incorporated"
			(at 227.0815 -57.6835 0)
			(layer "F.Fab")
			(hide yes)
			(effects
				(font
					(size 1 1)
					(thickness 0.15)
				)
			)
		)
		(sheetname "Supply")
		(sheetfile "supply.kicad_sch")
		(attr smd)
		(fp_line
			(start -0.277 -0.551)
			(end -0.277 -0.75)
			(stroke
				(width 0.15)
				(type solid)
			)
			(layer "F.SilkS")
		)
		(fp_line
			(start -0.725 -0.551)
			(end -0.277 -0.551)
			(stroke
				(width 0.15)
				(type solid)
			)
			(layer "F.SilkS")
		)
		(fp_line
			(start -0.927 -0.351)
			(end -0.725 -0.551)
			(stroke
				(width 0.15)
				(type solid)
			)
			(layer "F.SilkS")
		)
		(fp_line
			(start -0.927 -0.051)
			(end -0.927 -0.351)
			(stroke
				(width 0.15)
				(type solid)
			)
			(layer "F.SilkS")
		)
		(fp_circle
			(center -0.9652 0.9652)
			(end -0.9152 0.9652)
			(stroke
				(width 0.15)
				(type solid)
			)
			(fill yes)
			(layer "F.SilkS")
		)
		(fp_line
			(start 1.1 -1.16)
			(end 1.1 1.15)
			(stroke
				(width 0.05)
				(type solid)
			)
			(layer "F.CrtYd")
		)
		(fp_line
			(start -1.12 -1.16)
			(end 1.1 -1.16)
			(stroke
				(width 0.05)
				(type solid)
			)
			(layer "F.CrtYd")
		)
		(fp_line
			(start -1.12 -1.16)
			(end -1.12 1.15)
			(stroke
				(width 0.05)
				(type solid)
			)
			(layer "F.CrtYd")
		)
		(fp_line
			(start -1.12 1.15)
			(end 1.1 1.15)
			(stroke
				(width 0.05)
				(type solid)
			)
			(layer "F.CrtYd")
		)
		(fp_line
			(start 0.8 -0.425)
			(end -0.652 -0.425)
			(stroke
				(width 0.15)
				(type solid)
			)
			(layer "F.Fab")
		)
		(fp_line
			(start 0.8 -0.425)
			(end 0.8 0.424)
			(stroke
				(width 0.15)
				(type solid)
			)
			(layer "F.Fab")
		)
		(fp_line
			(start -0.652 -0.425)
			(end -0.802 -0.276)
			(stroke
				(width 0.15)
				(type solid)
			)
			(layer "F.Fab")
		)
		(fp_line
			(start -0.802 -0.276)
			(end -0.802 0.424)
			(stroke
				(width 0.15)
				(type solid)
			)
			(layer "F.Fab")
		)
		(fp_line
			(start 0.8 0.424)
			(end -0.802 0.424)
			(stroke
				(width 0.15)
				(type solid)
			)
			(layer "F.Fab")
		)
		(fp_circle
			(center -0.9652 0.9652)
			(end -0.9144 0.9652)
			(stroke
				(width 0.15)
				(type solid)
			)
			(fill no)
			(layer "F.Fab")
		)
		(pad "1" smd rect
			(at -0.5 0.65 90)
			(size 0.4 0.51)
			(layers "F.Cu" "F.Mask" "F.Paste")
			(net 465 "1V0_SYS")
			(pinfunction "G")
			(pintype "bidirectional")
		)
		(pad "2" smd rect
			(at 0.498 0.65 90)
			(size 0.4 0.51)
			(layers "F.Cu" "F.Mask" "F.Paste")
			(net 5 "GND")
			(pinfunction "S")
			(pintype "bidirectional")
		)
		(pad "3" smd rect
			(at 0 -0.652 90)
			(size 0.4 0.51)
			(layers "F.Cu" "F.Mask" "F.Paste")
			(net 237 "Net-(Q11-D)")
			(pinfunction "D")
			(pintype "bidirectional")
		)
	)
	(footprint "antmicro-footprints:R_0402_1005Metric"
		(layer "F.Cu")
		(at 123.65 88.974)
		(descr "Resistor SMD 0402")
		(tags "resistor SMD 0402")
		(property "Reference" "R150"
			(at -3.65 0.326 0)
			(layer "F.SilkS")
			(effects
				(font
					(size 0.7 0.7)
					(thickness 0.15)
				)
				(justify left bottom)
			)
		)
		(property "Value" "R_0R_0402"
			(at 0 1.4 0)
			(layer "F.Fab")
			(effects
				(font
					(size 0.7 0.7)
					(thickness 0.15)
				)
				(justify left bottom)
			)
		)
		(property "Description" "0R resistor in 0402 package with unspecified tolerance"
			(at 0 0 0)
			(layer "F.Fab")
			(hide yes)
			(effects
				(font
					(size 1.27 1.27)
					(thickness 0.15)
				)
			)
		)
		(property "Author" "Antmicro"
			(at 0 0 0)
			(layer "F.Fab")
			(hide yes)
			(effects
				(font
					(size 1 1)
					(thickness 0.15)
				)
			)
		)
		(property "Current" "1A"
			(at 0 0 0)
			(layer "F.Fab")
			(hide yes)
			(effects
				(font
					(size 1 1)
					(thickness 0.15)
				)
			)
		)
		(property "License" "Apache-2.0"
			(at 0 0 0)
			(layer "F.Fab")
			(hide yes)
			(effects
				(font
					(size 1 1)
					(thickness 0.15)
				)
			)
		)
		(property "MPN" "ERJ2GE0R00X"
			(at 0 0 0)
			(layer "F.Fab")
			(hide yes)
			(effects
				(font
					(size 1 1)
					(thickness 0.15)
				)
			)
		)
		(property "Manufacturer" "Panasonic"
			(at 0 0 0)
			(layer "F.Fab")
			(hide yes)
			(effects
				(font
					(size 1 1)
					(thickness 0.15)
				)
			)
		)
		(property "Tolerance" ""
			(at 0 0 0)
			(layer "F.Fab")
			(hide yes)
			(effects
				(font
					(size 1 1)
					(thickness 0.15)
				)
			)
		)
		(property "Val" "0R"
			(at 0 0 0)
			(layer "F.Fab")
			(hide yes)
			(effects
				(font
					(size 1 1)
					(thickness 0.15)
				)
			)
		)
		(sheetname "Supply")
		(sheetfile "supply.kicad_sch")
		(attr smd)
		(fp_rect
			(start -0.93 -0.47)
			(end 0.93 0.47)
			(stroke
				(width 0.05)
				(type solid)
			)
			(fill no)
			(layer "F.CrtYd")
		)
		(fp_rect
			(start -0.5 -0.25)
			(end 0.5 0.25)
			(stroke
				(width 0.15)
				(type solid)
			)
			(fill no)
			(layer "F.Fab")
		)
		(pad "1" smd roundrect
			(at -0.485 0)
			(size 0.59 0.64)
			(layers "F.Cu" "F.Mask" "F.Paste")
			(roundrect_rratio 0.25)
			(net 5 "GND")
			(pintype "passive")
		)
		(pad "2" smd roundrect
			(at 0.485 0)
			(size 0.59 0.64)
			(layers "F.Cu" "F.Mask" "F.Paste")
			(roundrect_rratio 0.25)
			(net 622 "/Supply/1V1_SS{slash}TR")
			(pintype "passive")
		)
	)
)
